# BASEBOARD_FAB2 (Tioga Pass) — schematic netlist excerpt (pin names and nets, part order shuffled) for the footprints in the layout excerpt that follows; sources: Cadence DE-HDL packaged netlist, KiCad conversion of Wiwynn_Tioga_Pass_MB.brd

R1D11  RES  100.0K 1% CHIP  pkg 0402  page 199 : A = A_HSC_LOW_EN ; B = AGND_HSC
R12W34  RES  0.0 5% CHIP  pkg 0402  page 226 : A = PU_VR_PVDDQ_KLM_FAULT1 ; B = PWRGD_PVDDQ_KLM
CT47  CAP  1000PF 50V 10% X7R  pkg 0402LF  page 219 : A = VR_PVDDQ_DEF_PH2_SW ; B = VR_PVDDQ_DEF_PH2_SW_RC

(kicad_pcb
	(version 20260206)
	(generator "pcbnew")
	(generator_version "10.0")
	(general
		(thickness 1.6)
		(legacy_teardrops no)
	)
	(paper "A4")
	(title_block
		(title "Wiwynn_Tioga_Pass_MB.brd")
		(comment 1 "Tioga Pass / footprints 2130-2132 of 4770")
	)
	(layers
		(0 "F.Cu" signal "TOP")
		(4 "In1.Cu" signal "L2GND")
		(6 "In2.Cu" signal "L3")
		(8 "In3.Cu" signal "L4GND")
		(10 "In4.Cu" signal "L5")
		(12 "In5.Cu" signal "L6GND")
		(14 "In6.Cu" signal "L7VCC")
		(16 "In7.Cu" signal "L8VCC")
		(18 "In8.Cu" signal "L9GND")
		(20 "In9.Cu" signal "L10")
		(22 "In10.Cu" signal "L11GND")
		(24 "In11.Cu" signal "L12")
		(26 "In12.Cu" signal "L13GND")
		(2 "B.Cu" signal "BOTTOM")
		(9 "F.Adhes" user "F.Adhesive")
		(11 "B.Adhes" user "B.Adhesive")
		(13 "F.Paste" user "Package Geometry/Pastemask Top")
		(15 "B.Paste" user "Package Geometry/Pastemask Bottom")
		(5 "F.SilkS" user "Ref Des/Silkscreen Top")
		(7 "B.SilkS" user "Ref Des/Silkscreen Bottom")
		(1 "F.Mask" user "Board Geometry/Soldermask Top")
		(3 "B.Mask" user "Board Geometry/Soldermask Bottom")
		(17 "Dwgs.User" user "User.Drawings")
		(19 "Cmts.User" user "User.Comments")
		(21 "Eco1.User" user "User.Eco1")
		(23 "Eco2.User" user "User.Eco2")
		(25 "Edge.Cuts" user "Board Geometry/Outline")
		(27 "Margin" user)
		(31 "F.CrtYd" user "Package Geometry/Place Bound Top")
		(29 "B.CrtYd" user "Package Geometry/Place Bound Bottom")
		(35 "F.Fab" user "Ref Des/Assembly Top")
		(33 "B.Fab" user "Ref Des/Assembly Bottom")
	)
	(footprint ""
		(layer "F.Cu")
		(at -2.667 -130.1242 -90)
		(property "Reference" "R12W34"
			(at -0.8382 -0.67818 270)
			(unlocked yes)
			(layer "F.SilkS")
			(effects
				(font
					(size 0.4064 0.254)
					(thickness 0.1524)
				)
				(justify left)
			)
		)
		(property "Value" ""
			(at 0 0 270)
			(layer "F.Fab")
			(effects
				(font
					(size 1.27 1.27)
				)
			)
		)
		(duplicate_pad_numbers_are_jumpers no)
		(fp_poly
			(pts
				(xy -0.2794 -0.1016) (xy 0.2794 -0.1016) (xy 0.2794 0.9906) (xy -0.2794 0.9906)
			)
			(stroke
				(width 0)
				(type default)
			)
			(fill no)
			(layer "F.CrtYd")
		)
		(fp_line
			(start -0.2794 0.9906)
			(end 0.2794 0.9906)
			(stroke
				(width 0.1)
				(type default)
			)
			(layer "F.Fab")
		)
		(fp_line
			(start 0.2794 0.9906)
			(end 0.2794 -0.1016)
			(stroke
				(width 0.1)
				(type default)
			)
			(layer "F.Fab")
		)
		(fp_line
			(start -0.2794 -0.1016)
			(end -0.2794 0.9906)
			(stroke
				(width 0.1)
				(type default)
			)
			(layer "F.Fab")
		)
		(fp_line
			(start 0.2794 -0.1016)
			(end -0.2794 -0.1016)
			(stroke
				(width 0.1)
				(type default)
			)
			(layer "F.Fab")
		)
		(pad "1" smd rect
			(at 0 0 270)
			(size 0.508 0.508)
			(layers "F.Cu" "F.Mask" "F.Paste")
			(net "PU_VR_PVDDQ_KLM_FAULT1")
		)
		(pad "2" smd rect
			(at 0 0.889 270)
			(size 0.508 0.508)
			(layers "F.Cu" "F.Mask" "F.Paste")
			(net "PWRGD_PVDDQ_KLM")
		)
		(zone
			(layer "F.Cu")
			(hatch none 0.5)
			(connect_pads
				(clearance 0)
			)
			(min_thickness 0.25)
			(keepout
				(tracks not_allowed)
				(vias allowed)
				(pads allowed)
				(copperpour not_allowed)
				(footprints allowed)
			)
			(placement
				(enabled no)
				(sheetname "")
			)
			(fill
				(thermal_gap 0.5)
				(thermal_bridge_width 0.5)
				(island_removal_mode 0)
			)
			(polygon
				(pts
					(xy -3.302 -130.3782) (xy -3.302 -129.8702) (xy -2.921 -129.8702) (xy -2.921 -130.3782)
				)
			)
		)
		(zone
			(layer "F.Cu")
			(hatch none 0.5)
			(connect_pads
				(clearance 0)
			)
			(min_thickness 0.25)
			(keepout
				(tracks allowed)
				(vias not_allowed)
				(pads allowed)
				(copperpour not_allowed)
				(footprints allowed)
			)
			(placement
				(enabled no)
				(sheetname "")
			)
			(fill
				(thermal_gap 0.5)
				(thermal_bridge_width 0.5)
				(island_removal_mode 0)
			)
			(polygon
				(pts
					(xy -2.921 -130.3782) (xy -2.921 -129.8702) (xy -3.302 -129.8702) (xy -3.302 -130.3782)
				)
			)
		)
	)
	(footprint ""
		(layer "F.Cu")
		(at 14.986 -84.963 -90)
		(property "Reference" "R1D11"
			(at 0 0 270)
			(layer "F.SilkS")
			(hide yes)
			(effects
				(font
					(size 1.27 1.27)
				)
			)
		)
		(property "Value" ""
			(at 0 0 270)
			(layer "F.Fab")
			(effects
				(font
					(size 1.27 1.27)
				)
			)
		)
		(duplicate_pad_numbers_are_jumpers no)
		(fp_poly
			(pts
				(xy -0.2794 -0.1016) (xy 0.2794 -0.1016) (xy 0.2794 0.9906) (xy -0.2794 0.9906)
			)
			(stroke
				(width 0)
				(type default)
			)
			(fill no)
			(layer "F.CrtYd")
		)
		(fp_line
			(start -0.2794 0.9906)
			(end 0.2794 0.9906)
			(stroke
				(width 0.1)
				(type default)
			)
			(layer "F.Fab")
		)
		(fp_line
			(start 0.2794 0.9906)
			(end 0.2794 -0.1016)
			(stroke
				(width 0.1)
				(type default)
			)
			(layer "F.Fab")
		)
		(fp_line
			(start -0.2794 -0.1016)
			(end -0.2794 0.9906)
			(stroke
				(width 0.1)
				(type default)
			)
			(layer "F.Fab")
		)
		(fp_line
			(start 0.2794 -0.1016)
			(end -0.2794 -0.1016)
			(stroke
				(width 0.1)
				(type default)
			)
			(layer "F.Fab")
		)
		(pad "1" smd rect
			(at 0 0 270)
			(size 0.508 0.508)
			(layers "F.Cu" "F.Mask" "F.Paste")
			(net "A_HSC_LOW_EN")
		)
		(pad "2" smd rect
			(at 0 0.889 270)
			(size 0.508 0.508)
			(layers "F.Cu" "F.Mask" "F.Paste")
			(net "AGND_HSC")
		)
		(zone
			(layer "F.Cu")
			(hatch none 0.5)
			(connect_pads
				(clearance 0)
			)
			(min_thickness 0.25)
			(keepout
				(tracks not_allowed)
				(vias allowed)
				(pads allowed)
				(copperpour not_allowed)
				(footprints allowed)
			)
			(placement
				(enabled no)
				(sheetname "")
			)
			(fill
				(thermal_gap 0.5)
				(thermal_bridge_width 0.5)
				(island_removal_mode 0)
			)
			(polygon
				(pts
					(xy 14.351 -85.217) (xy 14.351 -84.709) (xy 14.732 -84.709) (xy 14.732 -85.217)
				)
			)
		)
		(zone
			(layer "F.Cu")
			(hatch none 0.5)
			(connect_pads
				(clearance 0)
			)
			(min_thickness 0.25)
			(keepout
				(tracks allowed)
				(vias not_allowed)
				(pads allowed)
				(copperpour not_allowed)
				(footprints allowed)
			)
			(placement
				(enabled no)
				(sheetname "")
			)
			(fill
				(thermal_gap 0.5)
				(thermal_bridge_width 0.5)
				(island_removal_mode 0)
			)
			(polygon
				(pts
					(xy 14.732 -85.217) (xy 14.732 -84.709) (xy 14.351 -84.709) (xy 14.351 -85.217)
				)
			)
		)
	)
	(footprint ""
		(layer "F.Cu")
		(at 343.408 -143.2814)
		(property "Reference" "CT47"
			(at -0.8382 -0.67818 0)
			(unlocked yes)
			(layer "F.SilkS")
			(effects
				(font
					(size 0.4064 0.254)
					(thickness 0.1524)
				)
				(justify left)
			)
		)
		(property "Value" ""
			(at 0 0 0)
			(layer "F.Fab")
			(effects
				(font
					(size 1.27 1.27)
				)
			)
		)
		(duplicate_pad_numbers_are_jumpers no)
		(fp_poly
			(pts
				(xy 0.3048 -0.1016) (xy 0.3048 0.9906) (xy -0.3048 0.9906) (xy -0.3048 -0.1016)
			)
			(stroke
				(width 0)
				(type default)
			)
			(fill no)
			(layer "F.CrtYd")
		)
		(fp_line
			(start -0.3048 -0.1016)
			(end -0.3048 0.9906)
			(stroke
				(width 0.1)
				(type default)
			)
			(layer "F.Fab")
		)
		(fp_line
			(start -0.3048 0.9906)
			(end 0.3048 0.9906)
			(stroke
				(width 0.1)
				(type default)
			)
			(layer "F.Fab")
		)
		(fp_line
			(start 0.3048 -0.1016)
			(end -0.3048 -0.1016)
			(stroke
				(width 0.1)
				(type default)
			)
			(layer "F.Fab")
		)
		(fp_line
			(start 0.3048 0.9906)
			(end 0.3048 -0.1016)
			(stroke
				(width 0.1)
				(type default)
			)
			(layer "F.Fab")
		)
		(pad "1" smd rect
			(at 0 0)
			(size 0.508 0.508)
			(layers "F.Cu" "F.Mask" "F.Paste")
			(net "VR_PVDDQ_DEF_PH2_SW")
		)
		(pad "2" smd rect
			(at 0 0.889)
			(size 0.508 0.508)
			(layers "F.Cu" "F.Mask" "F.Paste")
			(net "VR_PVDDQ_DEF_PH2_SW_RC")
		)
		(zone
			(layer "F.Cu")
			(hatch none 0.5)
			(connect_pads
				(clearance 0)
			)
			(min_thickness 0.25)
			(keepout
				(tracks allowed)
				(vias not_allowed)
				(pads allowed)
				(copperpour not_allowed)
				(footprints allowed)
			)
			(placement
				(enabled no)
				(sheetname "")
			)
			(fill
				(thermal_gap 0.5)
				(thermal_bridge_width 0.5)
				(island_removal_mode 0)
			)
			(polygon
				(pts
					(xy 343.154 -143.0274) (xy 343.662 -143.0274) (xy 343.662 -142.6464) (xy 343.154 -142.6464)
				)
			)
		)
		(zone
			(layer "F.Cu")
			(hatch none 0.5)
			(connect_pads
				(clearance 0)
			)
			(min_thickness 0.25)
			(keepout
				(tracks not_allowed)
				(vias allowed)
				(pads allowed)
				(copperpour not_allowed)
				(footprints allowed)
			)
			(placement
				(enabled no)
				(sheetname "")
			)
			(fill
				(thermal_gap 0.5)
				(thermal_bridge_width 0.5)
				(island_removal_mode 0)
			)
			(polygon
				(pts
					(xy 343.154 -142.6464) (xy 343.662 -142.6464) (xy 343.662 -143.0274) (xy 343.154 -143.0274)
				)
			)
		)
	)
)
